# S9S_MB_2U (Grand Teton) — schematic netlist excerpt (pin names and nets, part order shuffled) for the footprints in the layout excerpt that follows; sources: Cadence DE-HDL packaged netlist, KiCad conversion of 03242023_DA0F0TMBIJ0_F0T_Motherboard_J_brd_V01_OCP.brd

J26  SCONN288_ADR50017P087CC  SCONN288_ADR50017-P087CC IO  pkg DDR288S_1-1VXB  page 107
  VIN_BULK0  = P12V_S3_AUX_CPU1_NVDIMM
  RFU0  = TP_CHE_CPU1_DIMM2_FRU_0
  VIN_MGMT  = P3V3_AUX
  HSCL  = I3C_SPD_DDREFGH_CPU1_LVC1_SCL_1
  HSDA  = I3C_SPD_DDREFGH_CPU1_LVC1_SDA
  VSS0  = GND
  DQ0_A  = M_E_CPU1_SA_DQ<0>
  VSS1  = GND
  DQ1_A  = M_E_CPU1_SA_DQ<1>
  VSS2  = GND
  DQS0_A_T  = M_E_CPU1_SA_DQS_DP<0>
  DQS0_A_C  = M_E_CPU1_SA_DQS_DN<0>
  VSS3  = GND
  DQ4_A  = M_E_CPU1_SA_DQ<4>
  VSS4  = GND
  DQ5_A  = M_E_CPU1_SA_DQ<5>
  VSS5  = GND
  DQ8_A  = M_E_CPU1_SA_DQ<8>
  VSS6  = GND
  DQ9_A  = M_E_CPU1_SA_DQ<9>
  VSS7  = GND
  DQS1_A_T  = M_E_CPU1_SA_DQS_DP<1>
  DQS1_A_C  = M_E_CPU1_SA_DQS_DN<1>
  VSS8  = GND
  DQ12_A  = M_E_CPU1_SA_DQ<12>
  VSS9  = GND
  DQ13_A  = M_E_CPU1_SA_DQ<13>
  VSS10  = GND
  DQ16_A  = M_E_CPU1_SA_DQ<16>
  VSS11  = GND
  DQ17_A  = M_E_CPU1_SA_DQ<17>
  VSS12  = GND
  DQS2_A_T  = M_E_CPU1_SA_DQS_DP<2>
  DQS2_A_C  = M_E_CPU1_SA_DQS_DN<2>
  VSS13  = GND
  DQ20_A  = M_E_CPU1_SA_DQ<20>
  VSS14  = GND
  DQ21_A  = M_E_CPU1_SA_DQ<21>
  VSS15  = GND
  DQ24_A  = M_E_CPU1_SA_DQ<24>
  VSS16  = GND
  DQ25_A  = M_E_CPU1_SA_DQ<25>
  VSS17  = GND
  DQS3_A_T  = M_E_CPU1_SA_DQS_DP<3>
  DQS3_A_C  = M_E_CPU1_SA_DQS_DN<3>
  VSS18  = GND
  DQ28_A  = M_E_CPU1_SA_DQ<28>
  VSS19  = GND
  DQ29_A  = M_E_CPU1_SA_DQ<29>
  VSS20  = GND
  CB0_A  = M_E_CPU1_SA_CB<0>
  VSS21  = GND
  CB1_A  = M_E_CPU1_SA_CB<1>
  VSS22  = GND
  DQS4_A_T  = M_E_CPU1_SA_DQS_DP<4>
  DQS4_A_C  = M_E_CPU1_SA_DQS_DN<4>
  VSS23  = GND
  CB4_A  = M_E_CPU1_SA_CB<4>
  VSS24  = GND
  CB5_A  = M_E_CPU1_SA_CB<5>
  VSS25  = GND
  ALERT_N  = M_E_CPU1_ALERT_N
  VSS26  = GND
  CS0_A_N  = M_E_CPU1_SA_CS_N<2>
  VSS27  = GND
  CA0_A  = M_E_CPU1_SA_CA<0>
  VSS28  = GND
  CA2_A  = M_E_CPU1_SA_CA<2>
  VSS29  = GND
  CA4_A  = M_E_CPU1_SA_CA<4>
  VSS30  = GND
  CA6_A  = M_E_CPU1_SA_CA<6>
  VSS31  = GND
  PAR_A  = M_E_CPU1_SA_PAR
  VSS32  = GND
  CA0_B  = M_E_CPU1_SB_CA<0>
  VSS33  = GND
  CA2_B  = M_E_CPU1_SB_CA<2>
  VSS34  = GND
  CA4_B  = M_E_CPU1_SB_CA<4>
  VSS35  = GND
  CA6_B  = M_E_CPU1_SB_CA<6>
  VSS36  = GND
  CS0_B_N  = M_E_CPU1_SB_CS_N<2>
  VSS37  = GND
  \lbd||rsp_a_n\  = M_E_CPU1_SA_RSP<1>
  \lbs||rsp_b_n\  = M_E_CPU1_SB_RSP<1>
  VSS38  = GND
  CB4_B  = M_E_CPU1_SB_CB<4>
  VSS39  = GND
  CB5_B  = M_E_CPU1_SB_CB<5>
  VSS40  = GND
  \dqs9_b_t||tdqs9_b_t||dbi4_b_n\  = M_E_CPU1_SB_DQS_DP<9>
  \dqs9_b_c||tdqs9_b_c\  = M_E_CPU1_SB_DQS_DN<9>
  VSS41  = GND
  CB0_B  = M_E_CPU1_SB_CB<0>
  VSS42  = GND
  CB1_B  = M_E_CPU1_SB_CB<1>
  VSS43  = GND
  DQ0_B  = M_E_CPU1_SB_DQ<0>
  VSS44  = GND
  DQ1_B  = M_E_CPU1_SB_DQ<1>
  VSS45  = GND
  DQS0_B_T  = M_E_CPU1_SB_DQS_DP<0>
  DQS0_B_C  = M_E_CPU1_SB_DQS_DN<0>
  VSS46  = GND
  DQ4_B  = M_E_CPU1_SB_DQ<4>
  VSS47  = GND
  DQ5_B  = M_E_CPU1_SB_DQ<5>
  VSS48  = GND
  DQ8_B  = M_E_CPU1_SB_DQ<8>
  VSS49  = GND
  DQ9_B  = M_E_CPU1_SB_DQ<9>
  VSS50  = GND
  DQS1_B_T  = M_E_CPU1_SB_DQS_DP<1>
  DQS1_B_C  = M_E_CPU1_SB_DQS_DN<1>
  VSS51  = GND
  DQ12_B  = M_E_CPU1_SB_DQ<12>
  VSS52  = GND
  DQ13_B  = M_E_CPU1_SB_DQ<13>
  VSS53  = GND
  DQ16_B  = M_E_CPU1_SB_DQ<16>
  VSS54  = GND
  DQ17_B  = M_E_CPU1_SB_DQ<17>
  VSS55  = GND
  DQS2_B_T  = M_E_CPU1_SB_DQS_DP<2>
  DQS2_B_C  = M_E_CPU1_SB_DQS_DN<2>
  VSS56  = GND
  DQ20_B  = M_E_CPU1_SB_DQ<20>
  VSS57  = GND
  DQ21_B  = M_E_CPU1_SB_DQ<21>
  VSS58  = GND
  DQ24_B  = M_E_CPU1_SB_DQ<24>
  VSS59  = GND
  DQ25_B  = M_E_CPU1_SB_DQ<25>
  VSS60  = GND
  DQS3_B_T  = M_E_CPU1_SB_DQS_DP<3>
  DQS3_B_C  = M_E_CPU1_SB_DQS_DN<3>
  VSS61  = GND
  DQ28_B  = M_E_CPU1_SB_DQ<28>
  VSS62  = GND
  DQ29_B  = M_E_CPU1_SB_DQ<29>
  VSS63  = GND
  RFU1  = TP_CHE_CPU1_DIMM2_FRU_1
  VIN_BULK1  = P12V_S3_AUX_CPU1_NVDIMM
  VIN_BULK2  = P12V_S3_AUX_CPU1_NVDIMM
  \pwr_good||fail_n\  = PWRGD_CHE_CPU1_DIMM2
  HSA  = PD_CHE_CPU1_DIMM2_SAA
  RFU2  = TP_CHE_CPU1_DIMM2_FRU_2
  RFU3  = TP_CHE_CPU1_DIMM2_FRU_3
  VSS64  = GND
  DQ2_A  = M_E_CPU1_SA_DQ<2>
  VSS65  = GND
  DQ3_A  = M_E_CPU1_SA_DQ<3>
  VSS66  = GND
  \dqs5_a_c||tdqs5_a_c||dqs5_a_t||tdqs5_a_t\  = M_E_CPU1_SA_DQS_DN<5>
  \dqs5_a_t||tdqs5_a_t\  = M_E_CPU1_SA_DQS_DP<5>
  VSS67  = GND
  DQ6_A  = M_E_CPU1_SA_DQ<6>
  VSS68  = GND
  DQ7_A  = M_E_CPU1_SA_DQ<7>
  VSS69  = GND
  DQ10_A  = M_E_CPU1_SA_DQ<10>
  VSS70  = GND
  DQ11_A  = M_E_CPU1_SA_DQ<11>
  VSS71  = GND
  \dqs6_a_c||tdqs6_a_c||dqs6_a_t||tdqs6_a_t\  = M_E_CPU1_SA_DQS_DN<6>
  \dqs6_a_t||tdqs6_a_t\  = M_E_CPU1_SA_DQS_DP<6>
  VSS72  = GND
  DQ14_A  = M_E_CPU1_SA_DQ<14>
  VSS73  = GND
  DQ15_A  = M_E_CPU1_SA_DQ<15>
  VSS74  = GND
  DQ18_A  = M_E_CPU1_SA_DQ<18>
  VSS75  = GND
  DQ19_A  = M_E_CPU1_SA_DQ<19>
  VSS76  = GND
  \dqs7_a_c||tdqs7_a_c\  = M_E_CPU1_SA_DQS_DN<7>
  \dqs7_a_t||tdqs7_a_t\  = M_E_CPU1_SA_DQS_DP<7>
  VSS77  = GND
  DQ22_A  = M_E_CPU1_SA_DQ<22>
  VSS78  = GND
  DQ23_A  = M_E_CPU1_SA_DQ<23>
  VSS79  = GND
  DQ26_A  = M_E_CPU1_SA_DQ<26>
  VSS80  = GND
  DQ27_A  = M_E_CPU1_SA_DQ<27>
  VSS81  = GND
  \dqs8_a_c||tdqs8_a_c\  = M_E_CPU1_SA_DQS_DN<8>
  \dqs8_a_t||tdqs8_a_t\  = M_E_CPU1_SA_DQS_DP<8>
  VSS82  = GND
  DQ30_A  = M_E_CPU1_SA_DQ<30>
  VSS83  = GND
  DQ31_A  = M_E_CPU1_SA_DQ<31>
  VSS84  = GND
  CB2_A  = M_E_CPU1_SA_CB<2>
  VSS85  = GND
  CB3_A  = M_E_CPU1_SA_CB<3>
  VSS86  = GND
  \dqs9_a_c||tdqs9_a_c\  = M_E_CPU1_SA_DQS_DN<9>
  \dqs9_a_t||tdqs9_a_t\  = M_E_CPU1_SA_DQS_DP<9>
  VSS87  = GND
  CB6_A  = M_E_CPU1_SA_CB<6>
  VSS88  = GND
  CB7_A  = M_E_CPU1_SA_CB<7>
  VSS89  = GND
  RESET_N  = RST_M_EF_CPU1_FPGA_N
  VSS90  = GND
  CS1_A_N  = M_E_CPU1_SA_CS_N<3>
  VSS91  = GND
  CA1_A  = M_E_CPU1_SA_CA<1>
  VSS92  = GND
  CA3_A  = M_E_CPU1_SA_CA<3>
  VSS93  = GND
  CA5_A  = M_E_CPU1_SA_CA<5>
  VSS94  = GND
  CK_T  = M_E_CPU1_CLK_DP<1>
  CK_C  = M_E_CPU1_CLK_DN<1>
  VSS95  = GND
  RFU4  = TP_CHE_CPU1_DIMM2_FRU_4
  CA1_B  = M_E_CPU1_SB_CA<1>
  VSS96  = GND
  CA3_B  = M_E_CPU1_SB_CA<3>
  VSS97  = GND
  CA5_B  = M_E_CPU1_SB_CA<5>
  VSS98  = GND
  PAR_B  = M_E_CPU1_SB_PAR
  VSS99  = GND
  CS1_B_N  = M_E_CPU1_SB_CS_N<3>
  VSS100  = GND
  RFU5  = TP_CHE_CPU1_DIMM2_FRU_5
  RFU6  = TP_CHE_CPU1_DIMM2_FRU_6
  VSS101  = GND
  CB6_B  = M_E_CPU1_SB_CB<6>
  VSS102  = GND
  CB7_B  = M_E_CPU1_SB_CB<7>
  VSS103  = GND
  DQS4_B_C  = M_E_CPU1_SB_DQS_DN<4>
  DQS4_B_T  = M_E_CPU1_SB_DQS_DP<4>
  VSS104  = GND
  CB2_B  = M_E_CPU1_SB_CB<2>
  VSS105  = GND
  CB3_B  = M_E_CPU1_SB_CB<3>
  VSS106  = GND
  DQ2_B  = M_E_CPU1_SB_DQ<2>
  VSS107  = GND
  DQ3_B  = M_E_CPU1_SB_DQ<3>
  VSS108  = GND
  \dqs5_b_c||tdqs5_b_c\  = M_E_CPU1_SB_DQS_DN<5>
  \dqs5_b_t||tdqs5_b_t\  = M_E_CPU1_SB_DQS_DP<5>
  VSS109  = GND
  DQ6_B  = M_E_CPU1_SB_DQ<6>
  VSS110  = GND
  DQ7_B  = M_E_CPU1_SB_DQ<7>
  VSS111  = GND
  DQ10_B  = M_E_CPU1_SB_DQ<10>
  VSS112  = GND
  DQ11_B  = M_E_CPU1_SB_DQ<11>
  VSS113  = GND
  \dqs6_b_c||tdqs6_b_c\  = M_E_CPU1_SB_DQS_DN<6>
  \dqs6_b_t||tdqs6_b_t\  = M_E_CPU1_SB_DQS_DP<6>
  VSS114  = GND
  DQ14_B  = M_E_CPU1_SB_DQ<14>
  VSS115  = GND
  DQ15_B  = M_E_CPU1_SB_DQ<15>
  VSS116  = GND
  DQ18_B  = M_E_CPU1_SB_DQ<18>
  VSS117  = GND
  DQ19_B  = M_E_CPU1_SB_DQ<19>
  VSS118  = GND
  \dqs7_b_c||tdqs7_b_c\  = M_E_CPU1_SB_DQS_DN<7>
  \dqs7_b_t||tdqs7_b_t\  = M_E_CPU1_SB_DQS_DP<7>
  VSS119  = GND
  DQ22_B  = M_E_CPU1_SB_DQ<22>
  VSS120  = GND
  DQ23_B  = M_E_CPU1_SB_DQ<23>
  VSS121  = GND
  DQ26_B  = M_E_CPU1_SB_DQ<26>
  VSS122  = GND
  DQ27_B  = M_E_CPU1_SB_DQ<27>
  VSS123  = GND
  \dqs8_b_c||tdqs8_b_c\  = M_E_CPU1_SB_DQS_DN<8>
  \dqs8_b_t||tdqs8_b_t\  = M_E_CPU1_SB_DQS_DP<8>
  VSS124  = GND
  DQ30_B  = M_E_CPU1_SB_DQ<30>
  VSS125  = GND
  DQ31_B  = M_E_CPU1_SB_DQ<31>
  VSS126  = GND
  G1  = GND
  G2  = GND
  G3  = GND

(kicad_pcb
	(version 20260206)
	(generator "pcbnew")
	(generator_version "10.0")
	(general
		(thickness 1.6)
		(legacy_teardrops no)
	)
	(paper "A4")
	(title_block
		(title "03242023_DA0F0TMBIJ0_F0T_Motherboard_J_brd_V01_OCP.brd")
		(comment 1 "Grand Teton / footprint 1065 of 6105 (J26), pads 275-291 of 291")
	)
	(layers
		(0 "F.Cu" signal "TOP")
		(4 "In1.Cu" signal "GND")
		(6 "In2.Cu" signal "IN1")
		(8 "In3.Cu" signal "GND1")
		(10 "In4.Cu" signal "IN2")
		(12 "In5.Cu" signal "GND2")
		(14 "In6.Cu" signal "IN3")
		(16 "In7.Cu" signal "GND3")
		(18 "In8.Cu" signal "VCC")
		(20 "In9.Cu" signal "VCC1")
		(22 "In10.Cu" signal "GND4")
		(24 "In11.Cu" signal "IN4")
		(26 "In12.Cu" signal "GND5")
		(28 "In13.Cu" signal "IN5")
		(30 "In14.Cu" signal "GND6")
		(32 "In15.Cu" signal "IN6")
		(34 "In16.Cu" signal "GND7")
		(2 "B.Cu" signal "BOTTOM")
		(9 "F.Adhes" user "F.Adhesive")
		(11 "B.Adhes" user "B.Adhesive")
		(13 "F.Paste" user "Package Geometry/Pastemask Top")
		(15 "B.Paste" user "Package Geometry/Pastemask Bottom")
		(5 "F.SilkS" user "Ref Des/Silkscreen Top")
		(7 "B.SilkS" user "Ref Des/Silkscreen Bottom")
		(1 "F.Mask" user "Board Geometry/Soldermask Top")
		(3 "B.Mask" user "Board Geometry/Soldermask Bottom")
		(17 "Dwgs.User" user "User.Drawings")
		(19 "Cmts.User" user "User.Comments")
		(21 "Eco1.User" user "User.Eco1")
		(23 "Eco2.User" user "User.Eco2")
		(25 "Edge.Cuts" user "Board Geometry/Outline")
		(27 "Margin" user)
		(31 "F.CrtYd" user "Package Geometry/Place Bound Top")
		(29 "B.CrtYd" user "Package Geometry/Place Bound Bottom")
		(35 "F.Fab" user "Ref Des/Assembly Top")
		(33 "B.Fab" user "Ref Des/Assembly Bottom")
	)
	(footprint ""
		(layer "F.Cu")
		(at 160.86328 -258.091686)
		(property "Reference" "J26"
			(at -3.683 -81.702148 0)
			(unlocked yes)
			(layer "F.SilkS")
			(effects
				(font
					(size 0.7874 0.5842)
					(thickness 0.1524)
				)
				(justify left)
			)
		)
		(property "Value" ""
			(at 0 0 0)
			(layer "F.Fab")
			(effects
				(font
					(size 1.27 1.27)
				)
			)
		)
		(duplicate_pad_numbers_are_jumpers no)
		(pad "275" smd rect
			(at 2.050034 52.274978 270)
			(size 0.519938 1.4986)
			(layers "F.Cu" "F.Mask" "F.Paste")
			(net "GND")
		)
		(pad "276" smd rect
			(at 2.050034 53.125116 270)
			(size 0.519938 1.4986)
			(layers "F.Cu" "F.Mask" "F.Paste")
			(net "M_E_CPU1_SB_DQ<23>")
		)
		(pad "277" smd rect
			(at 2.050034 53.975 270)
			(size 0.519938 1.4986)
			(layers "F.Cu" "F.Mask" "F.Paste")
			(net "GND")
		)
		(pad "278" smd rect
			(at 2.050034 54.824884 270)
			(size 0.519938 1.4986)
			(layers "F.Cu" "F.Mask" "F.Paste")
			(net "M_E_CPU1_SB_DQ<26>")
		)
		(pad "279" smd rect
			(at 2.050034 55.675022 270)
			(size 0.519938 1.4986)
			(layers "F.Cu" "F.Mask" "F.Paste")
			(net "GND")
		)
		(pad "280" smd rect
			(at 2.050034 56.524906 270)
			(size 0.519938 1.4986)
			(layers "F.Cu" "F.Mask" "F.Paste")
			(net "M_E_CPU1_SB_DQ<27>")
		)
		(pad "281" smd rect
			(at 2.050034 57.375044 270)
			(size 0.519938 1.4986)
			(layers "F.Cu" "F.Mask" "F.Paste")
			(net "GND")
		)
		(pad "282" smd rect
			(at 2.050034 58.224928 270)
			(size 0.519938 1.4986)
			(layers "F.Cu" "F.Mask" "F.Paste")
			(net "M_E_CPU1_SB_DQS_DN<8>")
		)
		(pad "283" smd rect
			(at 2.050034 59.075066 270)
			(size 0.519938 1.4986)
			(layers "F.Cu" "F.Mask" "F.Paste")
			(net "M_E_CPU1_SB_DQS_DP<8>")
		)
		(pad "284" smd rect
			(at 2.050034 59.92495 270)
			(size 0.519938 1.4986)
			(layers "F.Cu" "F.Mask" "F.Paste")
			(net "GND")
		)
		(pad "285" smd rect
			(at 2.050034 60.775088 270)
			(size 0.519938 1.4986)
			(layers "F.Cu" "F.Mask" "F.Paste")
			(net "M_E_CPU1_SB_DQ<30>")
		)
		(pad "286" smd rect
			(at 2.050034 61.624972 270)
			(size 0.519938 1.4986)
			(layers "F.Cu" "F.Mask" "F.Paste")
			(net "GND")
		)
		(pad "287" smd rect
			(at 2.050034 62.47511 270)
			(size 0.519938 1.4986)
			(layers "F.Cu" "F.Mask" "F.Paste")
			(net "M_E_CPU1_SB_DQ<31>")
		)
		(pad "288" smd rect
			(at 2.050034 63.324994 270)
			(size 0.519938 1.4986)
			(layers "F.Cu" "F.Mask" "F.Paste")
			(net "GND")
		)
		(pad "G1" thru_hole oval
			(at 0 -68.97497)
			(size 2.8194 1.5748)
			(drill oval 2.4384 1.1938)
			(layers "*.Cu" "*.Mask")
			(remove_unused_layers no)
			(net "GND")
			(clearance 0.127)
			(thermal_gap 0.127)
		)
		(pad "G2" thru_hole oval
			(at 0 3.875024)
			(size 2.8194 1.5748)
			(drill oval 2.4384 1.1938)
			(layers "*.Cu" "*.Mask")
			(remove_unused_layers no)
			(net "GND")
			(clearance 0.127)
			(thermal_gap 0.127)
		)
		(pad "G3" thru_hole oval
			(at 0 68.97497)
			(size 2.8194 1.5748)
			(drill oval 2.4384 1.1938)
			(layers "*.Cu" "*.Mask")
			(remove_unused_layers no)
			(net "GND")
			(clearance 0.127)
			(thermal_gap 0.127)
		)
	)
)
